(kicad_pcb
	(version 20260206)
	(generator "pcbnew")
	(generator_version "10.0")
	(general
		(thickness 1.6)
		(legacy_teardrops no)
	)
	(paper "A4")
	(title_block
		(title "9052_F0T_PDB_Converter_Brick_F_V03_1208_1600_OCP.brd")
		(comment 1 "Grand Teton / footprints 25-27 of 578")
	)
	(layers
		(0 "F.Cu" signal "TOP")
		(4 "In1.Cu" signal "GND")
		(6 "In2.Cu" signal "IN1")
		(8 "In3.Cu" signal "GND1")
		(10 "In4.Cu" signal "VCC")
		(12 "In5.Cu" signal "VCC1")
		(14 "In6.Cu" signal "GND2")
		(16 "In7.Cu" signal "IN2")
		(18 "In8.Cu" signal "GND3")
		(2 "B.Cu" signal "BOTTOM")
		(9 "F.Adhes" user "F.Adhesive")
		(11 "B.Adhes" user "B.Adhesive")
		(13 "F.Paste" user "Package Geometry/Pastemask Top")
		(15 "B.Paste" user "Package Geometry/Pastemask Bottom")
		(5 "F.SilkS" user "Ref Des/Silkscreen Top")
		(7 "B.SilkS" user "Ref Des/Silkscreen Bottom")
		(1 "F.Mask" user "Board Geometry/Soldermask Top")
		(3 "B.Mask" user "Board Geometry/Soldermask Bottom")
		(17 "Dwgs.User" user "User.Drawings")
		(19 "Cmts.User" user "User.Comments")
		(21 "Eco1.User" user "User.Eco1")
		(23 "Eco2.User" user "User.Eco2")
		(25 "Edge.Cuts" user "Board Geometry/Outline")
		(27 "Margin" user)
		(31 "F.CrtYd" user "Package Geometry/Place Bound Top")
		(29 "B.CrtYd" user "Package Geometry/Place Bound Bottom")
		(35 "F.Fab" user "Ref Des/Assembly Top")
		(33 "B.Fab" user "Ref Des/Assembly Bottom")
	)
	(footprint ""
		(layer "F.Cu")
		(at 266.586716 -33.341818 180)
		(property "Reference" "PR33"
			(at 0 0 180)
			(layer "F.SilkS")
			(hide yes)
			(effects
				(font
					(size 1.27 1.27)
				)
			)
		)
		(property "Value" ""
			(at 0 0 180)
			(layer "F.Fab")
			(effects
				(font
					(size 1.27 1.27)
				)
			)
		)
		(duplicate_pad_numbers_are_jumpers no)
		(fp_line
			(start 0.7874 0.4064)
			(end -0.7874 0.4064)
			(stroke
				(width 0.1524)
				(type default)
			)
			(layer "F.SilkS")
		)
		(fp_line
			(start 0.7874 -0.4064)
			(end 0.7874 0.4064)
			(stroke
				(width 0.1524)
				(type default)
			)
			(layer "F.SilkS")
		)
		(fp_line
			(start -0.7874 0.4064)
			(end -0.7874 -0.4064)
			(stroke
				(width 0.1524)
				(type default)
			)
			(layer "F.SilkS")
		)
		(fp_line
			(start -0.7874 -0.4064)
			(end 0.7874 -0.4064)
			(stroke
				(width 0.1524)
				(type default)
			)
			(layer "F.SilkS")
		)
		(fp_line
			(start 0.67945 0.3048)
			(end 0.120396 0.3048)
			(stroke
				(width 0.1)
				(type default)
			)
			(layer "F.Fab")
		)
		(fp_line
			(start 0.67945 -0.3048)
			(end 0.67945 0.3048)
			(stroke
				(width 0.1)
				(type default)
			)
			(layer "F.Fab")
		)
		(fp_line
			(start 0.12065 -0.2794)
			(end 0.12065 -0.3048)
			(stroke
				(width 0.1)
				(type default)
			)
			(layer "F.Fab")
		)
		(fp_line
			(start 0.12065 -0.3048)
			(end 0.67945 -0.3048)
			(stroke
				(width 0.1)
				(type default)
			)
			(layer "F.Fab")
		)
		(fp_line
			(start 0.120396 0.3048)
			(end 0.120396 0.2794)
			(stroke
				(width 0.1)
				(type default)
			)
			(layer "F.Fab")
		)
		(fp_line
			(start 0.120396 0.2794)
			(end -0.12065 0.2794)
			(stroke
				(width 0.1)
				(type default)
			)
			(layer "F.Fab")
		)
		(fp_line
			(start -0.12065 0.3048)
			(end -0.67945 0.3048)
			(stroke
				(width 0.1)
				(type default)
			)
			(layer "F.Fab")
		)
		(fp_line
			(start -0.12065 0.2794)
			(end -0.12065 0.3048)
			(stroke
				(width 0.1)
				(type default)
			)
			(layer "F.Fab")
		)
		(fp_line
			(start -0.12065 -0.2794)
			(end 0.12065 -0.2794)
			(stroke
				(width 0.1)
				(type default)
			)
			(layer "F.Fab")
		)
		(fp_line
			(start -0.12065 -0.305054)
			(end -0.12065 -0.2794)
			(stroke
				(width 0.1)
				(type default)
			)
			(layer "F.Fab")
		)
		(fp_line
			(start -0.67945 0.3048)
			(end -0.67945 -0.305054)
			(stroke
				(width 0.1)
				(type default)
			)
			(layer "F.Fab")
		)
		(fp_line
			(start -0.67945 -0.305054)
			(end -0.12065 -0.305054)
			(stroke
				(width 0.1)
				(type default)
			)
			(layer "F.Fab")
		)
		(pad "1" smd circle
			(at -0.40005 0 180)
			(size 0 0)
			(layers "F.Cu" "F.Mask" "F.Paste")
			(net "HS1_TMR1")
		)
		(pad "2" smd circle
			(at 0.40005 0 180)
			(size 0 0)
			(layers "F.Cu" "F.Mask" "F.Paste")
			(net "HS1_TMR2")
		)
	)
	(footprint ""
		(layer "F.Cu")
		(at 144.47012 -121.209816)
		(property "Reference" "PU2"
			(at -26.563066 -5.12953 0)
			(unlocked yes)
			(layer "F.SilkS")
			(effects
				(font
					(size 0.7874 0.5842)
					(thickness 0.1524)
				)
				(justify left)
			)
		)
		(property "Value" ""
			(at 0 0 0)
			(layer "F.Fab")
			(effects
				(font
					(size 1.27 1.27)
				)
			)
		)
		(duplicate_pad_numbers_are_jumpers no)
		(fp_line
			(start -26.519886 -4.299966)
			(end -26.519886 55.099966)
			(stroke
				(width 0.1524)
				(type default)
			)
			(layer "F.SilkS")
		)
		(fp_line
			(start -26.519886 55.099966)
			(end 11.279886 55.099966)
			(stroke
				(width 0.1524)
				(type default)
			)
			(layer "F.SilkS")
		)
		(fp_line
			(start -26.020014 -3.800094)
			(end -26.020014 54.59984)
			(stroke
				(width 0.1524)
				(type default)
			)
			(layer "F.SilkS")
		)
		(fp_line
			(start -26.020014 54.59984)
			(end 10.780014 54.59984)
			(stroke
				(width 0.1524)
				(type default)
			)
			(layer "F.SilkS")
		)
		(fp_line
			(start 10.780014 -3.800094)
			(end -26.020014 -3.800094)
			(stroke
				(width 0.1524)
				(type default)
			)
			(layer "F.SilkS")
		)
		(fp_line
			(start 10.780014 54.59984)
			(end 10.780014 -3.800094)
			(stroke
				(width 0.1524)
				(type default)
			)
			(layer "F.SilkS")
		)
		(fp_line
			(start 11.279886 -4.299966)
			(end -26.519886 -4.299966)
			(stroke
				(width 0.1524)
				(type default)
			)
			(layer "F.SilkS")
		)
		(fp_line
			(start 11.279886 55.099966)
			(end 11.279886 -4.299966)
			(stroke
				(width 0.1524)
				(type default)
			)
			(layer "F.SilkS")
		)
		(fp_poly
			(pts
				(xy 1.27 -7.44728) (xy -1.27 -7.44728) (xy 0 -4.90728)
			)
			(stroke
				(width 0)
				(type default)
			)
			(fill yes)
			(layer "F.SilkS")
		)
		(fp_line
			(start -26.020014 -3.800094)
			(end -26.020014 54.59984)
			(stroke
				(width 0.1)
				(type default)
			)
			(layer "F.Fab")
		)
		(fp_line
			(start -26.020014 54.59984)
			(end 10.780014 54.59984)
			(stroke
				(width 0.1)
				(type default)
			)
			(layer "F.Fab")
		)
		(fp_line
			(start 10.780014 -3.800094)
			(end -26.020014 -3.800094)
			(stroke
				(width 0.1)
				(type default)
			)
			(layer "F.Fab")
		)
		(fp_line
			(start 10.780014 54.59984)
			(end 10.780014 -3.800094)
			(stroke
				(width 0.1)
				(type default)
			)
			(layer "F.Fab")
		)
		(fp_poly
			(pts
				(xy 1.27 -7.44728) (xy -1.27 -7.44728) (xy 0 -4.90728)
			)
			(stroke
				(width 0)
				(type default)
			)
			(fill yes)
			(layer "F.Fab")
		)
		(pad "1" thru_hole rect
			(at 0 0 270)
			(size 2.3622 2.3622)
			(drill 1.6002)
			(layers "*.Cu" "*.Mask")
			(remove_unused_layers no)
			(net "P52V_HS_FILTER")
			(clearance -0.127)
			(padstack
				(mode front_inner_back)
				(layer "Inner"
					(shape circle)
					(size 2.3622 2.3622)
					(clearance -0.127)
				)
				(layer "B.Cu"
					(shape rect)
					(size 2.3622 2.3622)
					(clearance -0.127)
				)
			)
		)
		(pad "2" thru_hole circle
			(at -7.62 0 270)
			(size 2.3622 2.3622)
			(drill 1.6002)
			(layers "*.Cu" "*.Mask")
			(remove_unused_layers no)
			(net "BRICK_P12V0_ON_OFF_R")
			(clearance -0.127)
		)
		(pad "3" thru_hole circle
			(at -15.24 0 270)
			(size 2.3622 2.3622)
			(drill 1.6002)
			(layers "*.Cu" "*.Mask")
			(remove_unused_layers no)
			(net "GND")
			(clearance -0.127)
		)
		(pad "4" thru_hole circle
			(at -19.05 50.8 270)
			(size 3.1242 3.1242)
			(drill 2.1082)
			(layers "*.Cu" "*.Mask")
			(remove_unused_layers no)
			(net "GND")
			(clearance -0.254)
		)
		(pad "5" thru_hole circle
			(at -15.24 50.8 270)
			(size 3.1242 3.1242)
			(drill 2.1082)
			(layers "*.Cu" "*.Mask")
			(remove_unused_layers no)
			(net "GND")
			(clearance -0.254)
		)
		(pad "6" thru_hole circle
			(at 0 50.8 270)
			(size 3.1242 3.1242)
			(drill 2.1082)
			(layers "*.Cu" "*.Mask")
			(remove_unused_layers no)
			(net "P12V_BRICK")
			(clearance -0.254)
		)
		(pad "7" thru_hole circle
			(at 3.81 50.8 270)
			(size 3.1242 3.1242)
			(drill 2.1082)
			(layers "*.Cu" "*.Mask")
			(remove_unused_layers no)
			(net "P12V_BRICK")
			(clearance -0.254)
		)
		(pad "8" thru_hole circle
			(at -13.619988 53.34 270)
			(size 1.3208 1.3208)
			(drill 0.9144)
			(layers "*.Cu" "*.Mask")
			(remove_unused_layers no)
			(net "P12V_BRICK0_PWRGD")
			(clearance 0.0508)
			(thermal_gap 0.0508)
		)
		(pad "9" thru_hole circle
			(at -11.619992 53.34 270)
			(size 1.3208 1.3208)
			(drill 0.9144)
			(layers "*.Cu" "*.Mask")
			(remove_unused_layers no)
			(net "P12V_MB0_SENSE-")
			(clearance 0.0508)
			(thermal_gap 0.0508)
		)
		(pad "10" thru_hole circle
			(at -9.619996 53.34 270)
			(size 1.3208 1.3208)
			(drill 0.9144)
			(layers "*.Cu" "*.Mask")
			(remove_unused_layers no)
			(net "SMB_BRICK0_SDA")
			(clearance 0.0508)
			(thermal_gap 0.0508)
		)
		(pad "11" thru_hole circle
			(at -7.62 53.34 270)
			(size 1.3208 1.3208)
			(drill 0.9144)
			(layers "*.Cu" "*.Mask")
			(remove_unused_layers no)
			(net "SMB_BRICK0_ALERT")
			(clearance 0.0508)
			(thermal_gap 0.0508)
		)
		(pad "12" thru_hole circle
			(at -5.620004 53.34 270)
			(size 1.3208 1.3208)
			(drill 0.9144)
			(layers "*.Cu" "*.Mask")
			(remove_unused_layers no)
			(net "SMB_BRICK0_SCL")
			(clearance 0.0508)
			(thermal_gap 0.0508)
		)
		(pad "13" thru_hole circle
			(at -3.620008 53.34 270)
			(size 1.3208 1.3208)
			(drill 0.9144)
			(layers "*.Cu" "*.Mask")
			(remove_unused_layers no)
			(net "BRICK0_PMBADD")
			(clearance 0.0508)
			(thermal_gap 0.0508)
		)
		(pad "14" thru_hole circle
			(at -1.620012 53.34 270)
			(size 1.3208 1.3208)
			(drill 0.9144)
			(layers "*.Cu" "*.Mask")
			(remove_unused_layers no)
			(net "P12V_MB0_SENSE+")
			(clearance 0.0508)
			(thermal_gap 0.0508)
		)
	)
	(footprint ""
		(layer "F.Cu")
		(at 69.097906 -130.175)
		(property "Reference" "PC79"
			(at 0 0 0)
			(layer "F.SilkS")
			(hide yes)
			(effects
				(font
					(size 1.27 1.27)
				)
			)
		)
		(property "Value" ""
			(at 0 0 0)
			(layer "F.Fab")
			(effects
				(font
					(size 1.27 1.27)
				)
			)
		)
		(duplicate_pad_numbers_are_jumpers no)
		(fp_line
			(start -2.2098 -0.9398)
			(end 2.2098 -0.9398)
			(stroke
				(width 0.1524)
				(type default)
			)
			(layer "F.SilkS")
		)
		(fp_line
			(start -2.2098 0.9398)
			(end -2.2098 -0.9398)
			(stroke
				(width 0.1524)
				(type default)
			)
			(layer "F.SilkS")
		)
		(fp_line
			(start 2.2098 -0.9398)
			(end 2.2098 0.9398)
			(stroke
				(width 0.1524)
				(type default)
			)
			(layer "F.SilkS")
		)
		(fp_line
			(start 2.2098 0.9398)
			(end -2.2098 0.9398)
			(stroke
				(width 0.1524)
				(type default)
			)
			(layer "F.SilkS")
		)
		(fp_line
			(start -1.700022 -0.899922)
			(end 1.700022 -0.899922)
			(stroke
				(width 0.1)
				(type default)
			)
			(layer "F.Fab")
		)
		(fp_line
			(start -1.700022 0.899922)
			(end -1.700022 -0.899922)
			(stroke
				(width 0.1)
				(type default)
			)
			(layer "F.Fab")
		)
		(fp_line
			(start 1.700022 -0.899922)
			(end 1.700022 0.899922)
			(stroke
				(width 0.1)
				(type default)
			)
			(layer "F.Fab")
		)
		(fp_line
			(start 1.700022 0.899922)
			(end -1.700022 0.899922)
			(stroke
				(width 0.1)
				(type default)
			)
			(layer "F.Fab")
		)
		(pad "1" smd rect
			(at -1.4732 0 180)
			(size 1.1684 1.5748)
			(layers "F.Cu" "F.Mask" "F.Paste")
			(net "P52V_HS_FILTER")
		)
		(pad "2" smd rect
			(at 1.4732 0 180)
			(size 1.1684 1.5748)
			(layers "F.Cu" "F.Mask" "F.Paste")
			(net "GND")
		)
	)
)
